# T6G (Grand Teton) — schematic netlist excerpt (pin names and nets, part order shuffled) for the footprints in the layout excerpt that follows; sources: Cadence DE-HDL packaged netlist, KiCad conversion of 04192023_DAF0TMB3IC0_F0TG_MB_C_brd_V02_OCP.brd

C2214  Q_CAP  22UF 4V 20% X6S  pkg C0402  page 69 : A = PVDDCR_CPU1_P0 ; B = GND
R103  Q_RES  1K 1% EMPTY  pkg 0402LF  page 98 : A = P3V3 ; B = PWRGD_CHA_CPU1_DIMM0
C991  Q_CAP  100UF 4V 20% X6S  pkg C0805  page 312 : A = P1V8_CPU0_RT3_1A ; B = GND

(kicad_pcb
	(version 20260206)
	(generator "pcbnew")
	(generator_version "10.0")
	(general
		(thickness 1.6)
		(legacy_teardrops no)
	)
	(paper "A4")
	(title_block
		(title "04192023_DAF0TMB3IC0_F0TG_MB_C_brd_V02_OCP.brd")
		(comment 1 "Grand Teton / footprints 5141-5143 of 8354")
	)
	(layers
		(0 "F.Cu" signal "TOP")
		(4 "In1.Cu" signal "GND")
		(6 "In2.Cu" signal "IN1")
		(8 "In3.Cu" signal "GND1")
		(10 "In4.Cu" signal "IN2")
		(12 "In5.Cu" signal "GND2")
		(14 "In6.Cu" signal "IN3")
		(16 "In7.Cu" signal "GND3")
		(18 "In8.Cu" signal "VCC")
		(20 "In9.Cu" signal "VCC1")
		(22 "In10.Cu" signal "GND4")
		(24 "In11.Cu" signal "IN4")
		(26 "In12.Cu" signal "GND5")
		(28 "In13.Cu" signal "IN5")
		(30 "In14.Cu" signal "GND6")
		(32 "In15.Cu" signal "IN6")
		(34 "In16.Cu" signal "GND7")
		(2 "B.Cu" signal "BOTTOM")
		(9 "F.Adhes" user "F.Adhesive")
		(11 "B.Adhes" user "B.Adhesive")
		(13 "F.Paste" user "Package Geometry/Pastemask Top")
		(15 "B.Paste" user "Package Geometry/Pastemask Bottom")
		(5 "F.SilkS" user "Ref Des/Silkscreen Top")
		(7 "B.SilkS" user "Ref Des/Silkscreen Bottom")
		(1 "F.Mask" user "Board Geometry/Soldermask Top")
		(3 "B.Mask" user "Board Geometry/Soldermask Bottom")
		(17 "Dwgs.User" user "User.Drawings")
		(19 "Cmts.User" user "User.Comments")
		(21 "Eco1.User" user "User.Eco1")
		(23 "Eco2.User" user "User.Eco2")
		(25 "Edge.Cuts" user "Board Geometry/Outline")
		(27 "Margin" user)
		(31 "F.CrtYd" user "Package Geometry/Place Bound Top")
		(29 "B.CrtYd" user "Package Geometry/Place Bound Bottom")
		(35 "F.Fab" user "Ref Des/Assembly Top")
		(33 "B.Fab" user "Ref Des/Assembly Bottom")
	)
	(footprint ""
		(layer "B.Cu")
		(at 392.016234 -395.466062 -90)
		(property "Reference" "C991"
			(at 0 0 90)
			(layer "B.SilkS")
			(hide yes)
			(effects
				(font
					(size 1.27 1.27)
				)
				(justify mirror)
			)
		)
		(property "Value" ""
			(at 0 0 90)
			(layer "B.Fab")
			(effects
				(font
					(size 1.27 1.27)
				)
				(justify mirror)
			)
		)
		(duplicate_pad_numbers_are_jumpers no)
		(fp_line
			(start -1.524 0.762)
			(end 1.524 0.762)
			(stroke
				(width 0.1524)
				(type default)
			)
			(layer "B.SilkS")
		)
		(fp_line
			(start 1.524 0.762)
			(end 1.524 -0.762)
			(stroke
				(width 0.1524)
				(type default)
			)
			(layer "B.SilkS")
		)
		(fp_line
			(start -1.524 -0.762)
			(end -1.524 0.762)
			(stroke
				(width 0.1524)
				(type default)
			)
			(layer "B.SilkS")
		)
		(fp_line
			(start 1.524 -0.762)
			(end -1.524 -0.762)
			(stroke
				(width 0.1524)
				(type default)
			)
			(layer "B.SilkS")
		)
		(fp_line
			(start -1.1049 0.724916)
			(end -1.1049 -0.724916)
			(stroke
				(width 0.1)
				(type default)
			)
			(layer "B.Fab")
		)
		(fp_line
			(start 1.1049 0.724916)
			(end -1.1049 0.724916)
			(stroke
				(width 0.1)
				(type default)
			)
			(layer "B.Fab")
		)
		(fp_line
			(start -1.1049 -0.724916)
			(end 1.1049 -0.724916)
			(stroke
				(width 0.1)
				(type default)
			)
			(layer "B.Fab")
		)
		(fp_line
			(start 1.1049 -0.724916)
			(end 1.1049 0.724916)
			(stroke
				(width 0.1)
				(type default)
			)
			(layer "B.Fab")
		)
		(pad "1" smd rect
			(at 0.889 0 270)
			(size 1.016 1.27)
			(layers "B.Cu" "B.Mask" "B.Paste")
			(net "P1V8_CPU0_RT3_1A")
		)
		(pad "2" smd rect
			(at -0.889 0 270)
			(size 1.016 1.27)
			(layers "B.Cu" "B.Mask" "B.Paste")
			(net "GND")
		)
	)
	(footprint ""
		(layer "B.Cu")
		(at 56.073802 -193.996564)
		(property "Reference" "R103"
			(at 0 0 0)
			(layer "B.SilkS")
			(hide yes)
			(effects
				(font
					(size 1.27 1.27)
				)
				(justify mirror)
			)
		)
		(property "Value" ""
			(at 0 0 0)
			(layer "B.Fab")
			(effects
				(font
					(size 1.27 1.27)
				)
				(justify mirror)
			)
		)
		(duplicate_pad_numbers_are_jumpers no)
		(fp_line
			(start -0.7874 -0.4064)
			(end -0.7874 0.4064)
			(stroke
				(width 0.1524)
				(type default)
			)
			(layer "B.SilkS")
		)
		(fp_line
			(start -0.7874 0.4064)
			(end 0.7874 0.4064)
			(stroke
				(width 0.1524)
				(type default)
			)
			(layer "B.SilkS")
		)
		(fp_line
			(start 0.7874 -0.4064)
			(end -0.7874 -0.4064)
			(stroke
				(width 0.1524)
				(type default)
			)
			(layer "B.SilkS")
		)
		(fp_line
			(start 0.7874 0.4064)
			(end 0.7874 -0.4064)
			(stroke
				(width 0.1524)
				(type default)
			)
			(layer "B.SilkS")
		)
		(fp_line
			(start -0.67945 -0.3048)
			(end -0.67945 0.3048)
			(stroke
				(width 0.1)
				(type default)
			)
			(layer "B.Fab")
		)
		(fp_line
			(start -0.67945 0.3048)
			(end -0.120396 0.3048)
			(stroke
				(width 0.1)
				(type default)
			)
			(layer "B.Fab")
		)
		(fp_line
			(start -0.12065 -0.3048)
			(end -0.67945 -0.3048)
			(stroke
				(width 0.1)
				(type default)
			)
			(layer "B.Fab")
		)
		(fp_line
			(start -0.12065 -0.2794)
			(end -0.12065 -0.3048)
			(stroke
				(width 0.1)
				(type default)
			)
			(layer "B.Fab")
		)
		(fp_line
			(start -0.120396 0.2794)
			(end 0.12065 0.2794)
			(stroke
				(width 0.1)
				(type default)
			)
			(layer "B.Fab")
		)
		(fp_line
			(start -0.120396 0.3048)
			(end -0.120396 0.2794)
			(stroke
				(width 0.1)
				(type default)
			)
			(layer "B.Fab")
		)
		(fp_line
			(start 0.12065 -0.305054)
			(end 0.12065 -0.2794)
			(stroke
				(width 0.1)
				(type default)
			)
			(layer "B.Fab")
		)
		(fp_line
			(start 0.12065 -0.2794)
			(end -0.12065 -0.2794)
			(stroke
				(width 0.1)
				(type default)
			)
			(layer "B.Fab")
		)
		(fp_line
			(start 0.12065 0.2794)
			(end 0.12065 0.3048)
			(stroke
				(width 0.1)
				(type default)
			)
			(layer "B.Fab")
		)
		(fp_line
			(start 0.12065 0.3048)
			(end 0.67945 0.3048)
			(stroke
				(width 0.1)
				(type default)
			)
			(layer "B.Fab")
		)
		(fp_line
			(start 0.67945 -0.305054)
			(end 0.12065 -0.305054)
			(stroke
				(width 0.1)
				(type default)
			)
			(layer "B.Fab")
		)
		(fp_line
			(start 0.67945 0.3048)
			(end 0.67945 -0.305054)
			(stroke
				(width 0.1)
				(type default)
			)
			(layer "B.Fab")
		)
		(pad "1" smd circle
			(at 0.40005 0 180)
			(size 0 0)
			(layers "B.Cu" "B.Mask" "B.Paste")
			(net "P3V3")
		)
		(pad "2" smd circle
			(at -0.40005 0 180)
			(size 0 0)
			(layers "B.Cu" "B.Mask" "B.Paste")
			(net "PWRGD_CHA_CPU1_DIMM0")
		)
	)
	(footprint ""
		(layer "B.Cu")
		(at 369.900454 -268.41831)
		(property "Reference" "C2214"
			(at 0 0 0)
			(layer "B.SilkS")
			(hide yes)
			(effects
				(font
					(size 1.27 1.27)
				)
				(justify mirror)
			)
		)
		(property "Value" ""
			(at 0 0 0)
			(layer "B.Fab")
			(effects
				(font
					(size 1.27 1.27)
				)
				(justify mirror)
			)
		)
		(duplicate_pad_numbers_are_jumpers no)
		(fp_line
			(start -0.7874 -0.4064)
			(end -0.7874 0.4064)
			(stroke
				(width 0.1524)
				(type default)
			)
			(layer "B.SilkS")
		)
		(fp_line
			(start -0.7874 0.4064)
			(end 0.7874 0.4064)
			(stroke
				(width 0.1524)
				(type default)
			)
			(layer "B.SilkS")
		)
		(fp_line
			(start 0.7874 -0.4064)
			(end -0.7874 -0.4064)
			(stroke
				(width 0.1524)
				(type default)
			)
			(layer "B.SilkS")
		)
		(fp_line
			(start 0.7874 0.4064)
			(end 0.7874 -0.4064)
			(stroke
				(width 0.1524)
				(type default)
			)
			(layer "B.SilkS")
		)
		(fp_line
			(start -0.67945 -0.3048)
			(end -0.67945 0.3048)
			(stroke
				(width 0.1)
				(type default)
			)
			(layer "B.Fab")
		)
		(fp_line
			(start -0.67945 0.3048)
			(end -0.120396 0.3048)
			(stroke
				(width 0.1)
				(type default)
			)
			(layer "B.Fab")
		)
		(fp_line
			(start -0.12065 -0.3048)
			(end -0.67945 -0.3048)
			(stroke
				(width 0.1)
				(type default)
			)
			(layer "B.Fab")
		)
		(fp_line
			(start -0.12065 -0.2794)
			(end -0.12065 -0.3048)
			(stroke
				(width 0.1)
				(type default)
			)
			(layer "B.Fab")
		)
		(fp_line
			(start -0.120396 0.2794)
			(end 0.12065 0.2794)
			(stroke
				(width 0.1)
				(type default)
			)
			(layer "B.Fab")
		)
		(fp_line
			(start -0.120396 0.3048)
			(end -0.120396 0.2794)
			(stroke
				(width 0.1)
				(type default)
			)
			(layer "B.Fab")
		)
		(fp_line
			(start 0.12065 -0.305054)
			(end 0.12065 -0.2794)
			(stroke
				(width 0.1)
				(type default)
			)
			(layer "B.Fab")
		)
		(fp_line
			(start 0.12065 -0.2794)
			(end -0.12065 -0.2794)
			(stroke
				(width 0.1)
				(type default)
			)
			(layer "B.Fab")
		)
		(fp_line
			(start 0.12065 0.2794)
			(end 0.12065 0.3048)
			(stroke
				(width 0.1)
				(type default)
			)
			(layer "B.Fab")
		)
		(fp_line
			(start 0.12065 0.3048)
			(end 0.67945 0.3048)
			(stroke
				(width 0.1)
				(type default)
			)
			(layer "B.Fab")
		)
		(fp_line
			(start 0.67945 -0.305054)
			(end 0.12065 -0.305054)
			(stroke
				(width 0.1)
				(type default)
			)
			(layer "B.Fab")
		)
		(fp_line
			(start 0.67945 0.3048)
			(end 0.67945 -0.305054)
			(stroke
				(width 0.1)
				(type default)
			)
			(layer "B.Fab")
		)
		(pad "1" smd circle
			(at 0.40005 0 180)
			(size 0 0)
			(layers "B.Cu" "B.Mask" "B.Paste")
			(net "PVDDCR_CPU1_P0")
		)
		(pad "2" smd circle
			(at -0.40005 0 180)
			(size 0 0)
			(layers "B.Cu" "B.Mask" "B.Paste")
			(net "GND")
		)
	)
)
